(kicad_pcb
	(version 20260206)
	(generator "pcbnew")
	(generator_version "10.0")
	(general
		(thickness 1.6)
		(legacy_teardrops no)
	)
	(paper "A4")
	(title_block
		(title "01162023_DA0F0TEBIF0_F0T_Expander_BD_F_brd_V02_OCP.brd")
		(comment 1 "Grand Teton / footprints 4111-4116 of 9728")
	)
	(layers
		(0 "F.Cu" signal "TOP")
		(4 "In1.Cu" signal "GND")
		(6 "In2.Cu" signal "VCC")
		(8 "In3.Cu" signal "VCC1")
		(10 "In4.Cu" signal "GND1")
		(12 "In5.Cu" signal "IN1")
		(14 "In6.Cu" signal "GND2")
		(16 "In7.Cu" signal "IN2")
		(18 "In8.Cu" signal "GND3")
		(20 "In9.Cu" signal "IN3")
		(22 "In10.Cu" signal "GND4")
		(24 "In11.Cu" signal "IN4")
		(26 "In12.Cu" signal "GND5")
		(28 "In13.Cu" signal "IN5")
		(30 "In14.Cu" signal "GND6")
		(32 "In15.Cu" signal "IN6")
		(34 "In16.Cu" signal "GND7")
		(2 "B.Cu" signal "BOTTOM")
		(9 "F.Adhes" user "F.Adhesive")
		(11 "B.Adhes" user "B.Adhesive")
		(13 "F.Paste" user "Package Geometry/Pastemask Top")
		(15 "B.Paste" user "Package Geometry/Pastemask Bottom")
		(5 "F.SilkS" user "Ref Des/Silkscreen Top")
		(7 "B.SilkS" user "Ref Des/Silkscreen Bottom")
		(1 "F.Mask" user "Board Geometry/Soldermask Top")
		(3 "B.Mask" user "Board Geometry/Soldermask Bottom")
		(17 "Dwgs.User" user "User.Drawings")
		(19 "Cmts.User" user "User.Comments")
		(21 "Eco1.User" user "User.Eco1")
		(23 "Eco2.User" user "User.Eco2")
		(25 "Edge.Cuts" user "Board Geometry/Outline")
		(27 "Margin" user)
		(31 "F.CrtYd" user "Package Geometry/Place Bound Top")
		(29 "B.CrtYd" user "Package Geometry/Place Bound Bottom")
		(35 "F.Fab" user "Ref Des/Assembly Top")
		(33 "B.Fab" user "Ref Des/Assembly Bottom")
	)
	(footprint ""
		(layer "F.Cu")
		(at 214.757 -193.548)
		(property "Reference" "U122"
			(at -1.594866 2.187702 0)
			(unlocked yes)
			(layer "F.SilkS")
			(effects
				(font
					(size 0.7874 0.5842)
					(thickness 0.1524)
				)
				(justify left)
			)
		)
		(property "Value" ""
			(at 0 0 0)
			(layer "F.Fab")
			(effects
				(font
					(size 1.27 1.27)
				)
			)
		)
		(duplicate_pad_numbers_are_jumpers no)
		(fp_line
			(start -1.3208 -1.525016)
			(end -0.508 -1.525016)
			(stroke
				(width 0.1524)
				(type default)
			)
			(layer "F.SilkS")
		)
		(fp_line
			(start -1.3208 1.525016)
			(end -1.3208 -1.525016)
			(stroke
				(width 0.1524)
				(type default)
			)
			(layer "F.SilkS")
		)
		(fp_line
			(start -0.508 -1.525016)
			(end 0 -0.999998)
			(stroke
				(width 0.1524)
				(type default)
			)
			(layer "F.SilkS")
		)
		(fp_line
			(start 0 -0.999998)
			(end 0.508 -1.525016)
			(stroke
				(width 0.1524)
				(type default)
			)
			(layer "F.SilkS")
		)
		(fp_line
			(start 0.508 -1.525016)
			(end 1.3208 -1.525016)
			(stroke
				(width 0.1524)
				(type default)
			)
			(layer "F.SilkS")
		)
		(fp_line
			(start 1.3208 -1.525016)
			(end 1.3208 1.525016)
			(stroke
				(width 0.1524)
				(type default)
			)
			(layer "F.SilkS")
		)
		(fp_line
			(start 1.3208 1.525016)
			(end -1.3208 1.525016)
			(stroke
				(width 0.1524)
				(type default)
			)
			(layer "F.SilkS")
		)
		(fp_poly
			(pts
				(xy -2.850134 -1.390396) (xy -3.658362 -1.65989) (xy -3.119374 -2.198624)
			)
			(stroke
				(width 0)
				(type default)
			)
			(fill yes)
			(layer "F.SilkS")
		)
		(fp_line
			(start -3.037078 -1.20777)
			(end -1.524 -1.20777)
			(stroke
				(width 0.1)
				(type default)
			)
			(layer "F.Fab")
		)
		(fp_line
			(start -3.037078 1.203706)
			(end -3.037078 -1.20777)
			(stroke
				(width 0.1)
				(type default)
			)
			(layer "F.Fab")
		)
		(fp_line
			(start -1.5494 1.203706)
			(end -3.037078 1.203706)
			(stroke
				(width 0.1)
				(type default)
			)
			(layer "F.Fab")
		)
		(fp_line
			(start -1.5494 1.5494)
			(end -1.5494 1.203706)
			(stroke
				(width 0.1)
				(type default)
			)
			(layer "F.Fab")
		)
		(fp_line
			(start -1.524 -1.524)
			(end 1.524 -1.524)
			(stroke
				(width 0.1)
				(type default)
			)
			(layer "F.Fab")
		)
		(fp_line
			(start -1.524 -1.20777)
			(end -1.524 -1.524)
			(stroke
				(width 0.1)
				(type default)
			)
			(layer "F.Fab")
		)
		(fp_line
			(start 1.524 -1.524)
			(end 1.524 -1.20777)
			(stroke
				(width 0.1)
				(type default)
			)
			(layer "F.Fab")
		)
		(fp_line
			(start 1.524 -1.20777)
			(end 3.0353 -1.20777)
			(stroke
				(width 0.1)
				(type default)
			)
			(layer "F.Fab")
		)
		(fp_line
			(start 1.524 1.208786)
			(end 1.524 1.5494)
			(stroke
				(width 0.1)
				(type default)
			)
			(layer "F.Fab")
		)
		(fp_line
			(start 1.524 1.5494)
			(end -1.5494 1.5494)
			(stroke
				(width 0.1)
				(type default)
			)
			(layer "F.Fab")
		)
		(fp_line
			(start 3.0353 -1.20777)
			(end 3.0353 1.208786)
			(stroke
				(width 0.1)
				(type default)
			)
			(layer "F.Fab")
		)
		(fp_line
			(start 3.0353 1.208786)
			(end 1.524 1.208786)
			(stroke
				(width 0.1)
				(type default)
			)
			(layer "F.Fab")
		)
		(fp_poly
			(pts
				(xy -3.175 -1.016) (xy -3.937 -0.635) (xy -3.937 -1.397)
			)
			(stroke
				(width 0)
				(type default)
			)
			(fill yes)
			(layer "F.Fab")
		)
		(pad "1" smd rect
			(at -2.234946 -0.975106 270)
			(size 0.3556 1.4986)
			(layers "F.Cu" "F.Mask" "F.Paste")
			(net "P1V2_AUX")
		)
		(pad "2" smd rect
			(at -2.234946 -0.32512 270)
			(size 0.3556 1.4986)
			(layers "F.Cu" "F.Mask" "F.Paste")
			(net "SMB_NIC7_R_SDA")
		)
		(pad "3" smd rect
			(at -2.234946 0.32512 270)
			(size 0.3556 1.4986)
			(layers "F.Cu" "F.Mask" "F.Paste")
			(net "SMB_NIC7_R_SCL")
		)
		(pad "4" smd rect
			(at -2.234946 0.975106 270)
			(size 0.3556 1.4986)
			(layers "F.Cu" "F.Mask" "F.Paste")
			(net "GND")
		)
		(pad "5" smd rect
			(at 2.234946 0.975106 270)
			(size 0.3556 1.4986)
			(layers "F.Cu" "F.Mask" "F.Paste")
			(net "SMB_NIC7_LS_EN")
		)
		(pad "6" smd rect
			(at 2.234946 0.32512 270)
			(size 0.3556 1.4986)
			(layers "F.Cu" "F.Mask" "F.Paste")
			(net "SMB_NIC7_LS_R_SCL")
		)
		(pad "7" smd rect
			(at 2.234946 -0.32512 270)
			(size 0.3556 1.4986)
			(layers "F.Cu" "F.Mask" "F.Paste")
			(net "SMB_NIC7_LS_R_SDA")
		)
		(pad "8" smd rect
			(at 2.234946 -0.975106 270)
			(size 0.3556 1.4986)
			(layers "F.Cu" "F.Mask" "F.Paste")
			(net "P3V3_NIC7")
		)
	)
	(footprint ""
		(layer "F.Cu")
		(at 457.211684 -365.543084 90)
		(property "Reference" "R6692"
			(at 0 0 90)
			(layer "F.SilkS")
			(hide yes)
			(effects
				(font
					(size 1.27 1.27)
				)
			)
		)
		(property "Value" ""
			(at 0 0 90)
			(layer "F.Fab")
			(effects
				(font
					(size 1.27 1.27)
				)
			)
		)
		(duplicate_pad_numbers_are_jumpers no)
		(fp_line
			(start 0.7874 -0.4064)
			(end 0.7874 0.4064)
			(stroke
				(width 0.1524)
				(type default)
			)
			(layer "F.SilkS")
		)
		(fp_line
			(start -0.7874 -0.4064)
			(end 0.7874 -0.4064)
			(stroke
				(width 0.1524)
				(type default)
			)
			(layer "F.SilkS")
		)
		(fp_line
			(start 0.7874 0.4064)
			(end -0.7874 0.4064)
			(stroke
				(width 0.1524)
				(type default)
			)
			(layer "F.SilkS")
		)
		(fp_line
			(start -0.7874 0.4064)
			(end -0.7874 -0.4064)
			(stroke
				(width 0.1524)
				(type default)
			)
			(layer "F.SilkS")
		)
		(fp_line
			(start -0.12065 -0.305054)
			(end -0.12065 -0.2794)
			(stroke
				(width 0.1)
				(type default)
			)
			(layer "F.Fab")
		)
		(fp_line
			(start -0.67945 -0.305054)
			(end -0.12065 -0.305054)
			(stroke
				(width 0.1)
				(type default)
			)
			(layer "F.Fab")
		)
		(fp_line
			(start 0.67945 -0.3048)
			(end 0.67945 0.3048)
			(stroke
				(width 0.1)
				(type default)
			)
			(layer "F.Fab")
		)
		(fp_line
			(start 0.12065 -0.3048)
			(end 0.67945 -0.3048)
			(stroke
				(width 0.1)
				(type default)
			)
			(layer "F.Fab")
		)
		(fp_line
			(start 0.12065 -0.2794)
			(end 0.12065 -0.3048)
			(stroke
				(width 0.1)
				(type default)
			)
			(layer "F.Fab")
		)
		(fp_line
			(start -0.12065 -0.2794)
			(end 0.12065 -0.2794)
			(stroke
				(width 0.1)
				(type default)
			)
			(layer "F.Fab")
		)
		(fp_line
			(start 0.120396 0.2794)
			(end -0.12065 0.2794)
			(stroke
				(width 0.1)
				(type default)
			)
			(layer "F.Fab")
		)
		(fp_line
			(start -0.12065 0.2794)
			(end -0.12065 0.3048)
			(stroke
				(width 0.1)
				(type default)
			)
			(layer "F.Fab")
		)
		(fp_line
			(start 0.67945 0.3048)
			(end 0.120396 0.3048)
			(stroke
				(width 0.1)
				(type default)
			)
			(layer "F.Fab")
		)
		(fp_line
			(start 0.120396 0.3048)
			(end 0.120396 0.2794)
			(stroke
				(width 0.1)
				(type default)
			)
			(layer "F.Fab")
		)
		(fp_line
			(start -0.12065 0.3048)
			(end -0.67945 0.3048)
			(stroke
				(width 0.1)
				(type default)
			)
			(layer "F.Fab")
		)
		(fp_line
			(start -0.67945 0.3048)
			(end -0.67945 -0.305054)
			(stroke
				(width 0.1)
				(type default)
			)
			(layer "F.Fab")
		)
		(pad "1" smd circle
			(at -0.40005 0 90)
			(size 0 0)
			(layers "F.Cu" "F.Mask" "F.Paste")
			(net "GPU_3V3IO_RSVD4_ISO_R")
		)
		(pad "2" smd circle
			(at 0.40005 0 90)
			(size 0 0)
			(layers "F.Cu" "F.Mask" "F.Paste")
			(net "GPU_3V3IO_RSVD4_ISO")
		)
	)
	(footprint ""
		(layer "F.Cu")
		(at 171.255182 -53.468524 90)
		(property "Reference" "PC511"
			(at 0 0 90)
			(layer "F.SilkS")
			(hide yes)
			(effects
				(font
					(size 1.27 1.27)
				)
			)
		)
		(property "Value" ""
			(at 0 0 90)
			(layer "F.Fab")
			(effects
				(font
					(size 1.27 1.27)
				)
			)
		)
		(duplicate_pad_numbers_are_jumpers no)
		(fp_line
			(start 1.524 -0.762)
			(end 1.524 0.762)
			(stroke
				(width 0.1524)
				(type default)
			)
			(layer "F.SilkS")
		)
		(fp_line
			(start -1.524 -0.762)
			(end 1.524 -0.762)
			(stroke
				(width 0.1524)
				(type default)
			)
			(layer "F.SilkS")
		)
		(fp_line
			(start 1.524 0.762)
			(end -1.524 0.762)
			(stroke
				(width 0.1524)
				(type default)
			)
			(layer "F.SilkS")
		)
		(fp_line
			(start -1.524 0.762)
			(end -1.524 -0.762)
			(stroke
				(width 0.1524)
				(type default)
			)
			(layer "F.SilkS")
		)
		(fp_line
			(start 1.1049 -0.724916)
			(end -1.1049 -0.724916)
			(stroke
				(width 0.1)
				(type default)
			)
			(layer "F.Fab")
		)
		(fp_line
			(start -1.1049 -0.724916)
			(end -1.1049 0.724916)
			(stroke
				(width 0.1)
				(type default)
			)
			(layer "F.Fab")
		)
		(fp_line
			(start 1.1049 0.724916)
			(end 1.1049 -0.724916)
			(stroke
				(width 0.1)
				(type default)
			)
			(layer "F.Fab")
		)
		(fp_line
			(start -1.1049 0.724916)
			(end 1.1049 0.724916)
			(stroke
				(width 0.1)
				(type default)
			)
			(layer "F.Fab")
		)
		(pad "1" smd rect
			(at -0.889 0 270)
			(size 1.016 1.27)
			(layers "F.Cu" "F.Mask" "F.Paste")
			(net "GND")
		)
		(pad "2" smd rect
			(at 0.889 0 270)
			(size 1.016 1.27)
			(layers "F.Cu" "F.Mask" "F.Paste")
			(net "P3V3_AUX")
		)
	)
	(footprint ""
		(layer "F.Cu")
		(at 399.639282 -177.428398 -90)
		(property "Reference" "Q7"
			(at 0.542798 1.721612 90)
			(unlocked yes)
			(layer "F.SilkS")
			(effects
				(font
					(size 0.7874 0.5842)
					(thickness 0.1524)
				)
				(justify left)
			)
		)
		(property "Value" ""
			(at 0 0 270)
			(layer "F.Fab")
			(effects
				(font
					(size 1.27 1.27)
				)
			)
		)
		(duplicate_pad_numbers_are_jumpers no)
		(fp_line
			(start -1.38176 1.100074)
			(end 1.38176 1.100074)
			(stroke
				(width 0.1524)
				(type default)
			)
			(layer "F.SilkS")
		)
		(fp_line
			(start 1.38176 1.100074)
			(end 1.38176 -1.100074)
			(stroke
				(width 0.1524)
				(type default)
			)
			(layer "F.SilkS")
		)
		(fp_line
			(start 0 -0.508)
			(end -0.592074 -1.100074)
			(stroke
				(width 0.1524)
				(type default)
			)
			(layer "F.SilkS")
		)
		(fp_line
			(start -1.38176 -1.100074)
			(end -1.38176 1.100074)
			(stroke
				(width 0.1524)
				(type default)
			)
			(layer "F.SilkS")
		)
		(fp_line
			(start -0.592074 -1.100074)
			(end -1.38176 -1.100074)
			(stroke
				(width 0.1524)
				(type default)
			)
			(layer "F.SilkS")
		)
		(fp_line
			(start 0.592074 -1.100074)
			(end 0 -0.508)
			(stroke
				(width 0.1524)
				(type default)
			)
			(layer "F.SilkS")
		)
		(fp_line
			(start 1.38176 -1.100074)
			(end 0.592074 -1.100074)
			(stroke
				(width 0.1524)
				(type default)
			)
			(layer "F.SilkS")
		)
		(fp_poly
			(pts
				(xy -0.68453 -1.603756) (xy -0.904748 -1.163066) (xy -1.124966 -1.603756)
			)
			(stroke
				(width 0)
				(type default)
			)
			(fill yes)
			(layer "F.SilkS")
		)
		(fp_line
			(start -0.674878 1.100074)
			(end 0.674878 1.100074)
			(stroke
				(width 0.1)
				(type default)
			)
			(layer "F.Fab")
		)
		(fp_line
			(start 0.674878 1.100074)
			(end 0.674878 -1.100074)
			(stroke
				(width 0.1)
				(type default)
			)
			(layer "F.Fab")
		)
		(fp_line
			(start -0.674878 -1.100074)
			(end -0.674878 1.100074)
			(stroke
				(width 0.1)
				(type default)
			)
			(layer "F.Fab")
		)
		(fp_line
			(start 0.674878 -1.100074)
			(end -0.674878 -1.100074)
			(stroke
				(width 0.1)
				(type default)
			)
			(layer "F.Fab")
		)
		(fp_poly
			(pts
				(xy -1.9431 -0.870204) (xy -1.50241 -0.649986) (xy -1.9431 -0.429768)
			)
			(stroke
				(width 0)
				(type default)
			)
			(fill yes)
			(layer "F.Fab")
		)
		(pad "1" smd rect
			(at -0.94996 -0.649986 180)
			(size 0.4318 0.6096)
			(layers "F.Cu" "F.Mask" "F.Paste")
			(net "GND")
		)
		(pad "2" smd rect
			(at -0.94996 0 180)
			(size 0.4318 0.6096)
			(layers "F.Cu" "F.Mask" "F.Paste")
			(net "HP_NIC6_HSC_PWRGD_N")
		)
		(pad "3" smd rect
			(at -0.94996 0.649986 180)
			(size 0.4318 0.6096)
			(layers "F.Cu" "F.Mask" "F.Paste")
			(net "HP_NIC6_HSC_PWRGD_N")
		)
		(pad "4" smd rect
			(at 0.94996 0.649986 180)
			(size 0.4318 0.6096)
			(layers "F.Cu" "F.Mask" "F.Paste")
			(net "GND")
		)
		(pad "5" smd rect
			(at 0.94996 0 180)
			(size 0.4318 0.6096)
			(layers "F.Cu" "F.Mask" "F.Paste")
			(net "PWRGD_P12V_NIC6_R")
		)
		(pad "6" smd rect
			(at 0.94996 -0.649986 180)
			(size 0.4318 0.6096)
			(layers "F.Cu" "F.Mask" "F.Paste")
			(net "HP_NIC6_PWRGD_R")
		)
	)
	(footprint ""
		(layer "F.Cu")
		(at 220.36786 -55.083456)
		(property "Reference" "PC384"
			(at 0 0 0)
			(layer "F.SilkS")
			(hide yes)
			(effects
				(font
					(size 1.27 1.27)
				)
			)
		)
		(property "Value" ""
			(at 0 0 0)
			(layer "F.Fab")
			(effects
				(font
					(size 1.27 1.27)
				)
			)
		)
		(duplicate_pad_numbers_are_jumpers no)
		(fp_line
			(start -0.7874 -0.4064)
			(end 0.7874 -0.4064)
			(stroke
				(width 0.1524)
				(type default)
			)
			(layer "F.SilkS")
		)
		(fp_line
			(start -0.7874 0.4064)
			(end -0.7874 -0.4064)
			(stroke
				(width 0.1524)
				(type default)
			)
			(layer "F.SilkS")
		)
		(fp_line
			(start 0.7874 -0.4064)
			(end 0.7874 0.4064)
			(stroke
				(width 0.1524)
				(type default)
			)
			(layer "F.SilkS")
		)
		(fp_line
			(start 0.7874 0.4064)
			(end -0.7874 0.4064)
			(stroke
				(width 0.1524)
				(type default)
			)
			(layer "F.SilkS")
		)
		(fp_line
			(start -0.67945 -0.305054)
			(end -0.12065 -0.305054)
			(stroke
				(width 0.1)
				(type default)
			)
			(layer "F.Fab")
		)
		(fp_line
			(start -0.67945 0.3048)
			(end -0.67945 -0.305054)
			(stroke
				(width 0.1)
				(type default)
			)
			(layer "F.Fab")
		)
		(fp_line
			(start -0.12065 -0.305054)
			(end -0.12065 -0.2794)
			(stroke
				(width 0.1)
				(type default)
			)
			(layer "F.Fab")
		)
		(fp_line
			(start -0.12065 -0.2794)
			(end 0.12065 -0.2794)
			(stroke
				(width 0.1)
				(type default)
			)
			(layer "F.Fab")
		)
		(fp_line
			(start -0.12065 0.2794)
			(end -0.12065 0.3048)
			(stroke
				(width 0.1)
				(type default)
			)
			(layer "F.Fab")
		)
		(fp_line
			(start -0.12065 0.3048)
			(end -0.67945 0.3048)
			(stroke
				(width 0.1)
				(type default)
			)
			(layer "F.Fab")
		)
		(fp_line
			(start 0.120396 0.2794)
			(end -0.12065 0.2794)
			(stroke
				(width 0.1)
				(type default)
			)
			(layer "F.Fab")
		)
		(fp_line
			(start 0.120396 0.3048)
			(end 0.120396 0.2794)
			(stroke
				(width 0.1)
				(type default)
			)
			(layer "F.Fab")
		)
		(fp_line
			(start 0.12065 -0.3048)
			(end 0.67945 -0.3048)
			(stroke
				(width 0.1)
				(type default)
			)
			(layer "F.Fab")
		)
		(fp_line
			(start 0.12065 -0.2794)
			(end 0.12065 -0.3048)
			(stroke
				(width 0.1)
				(type default)
			)
			(layer "F.Fab")
		)
		(fp_line
			(start 0.67945 -0.3048)
			(end 0.67945 0.3048)
			(stroke
				(width 0.1)
				(type default)
			)
			(layer "F.Fab")
		)
		(fp_line
			(start 0.67945 0.3048)
			(end 0.120396 0.3048)
			(stroke
				(width 0.1)
				(type default)
			)
			(layer "F.Fab")
		)
		(pad "1" smd circle
			(at -0.40005 0)
			(size 0 0)
			(layers "F.Cu" "F.Mask" "F.Paste")
			(net "P5V_AUX")
		)
		(pad "2" smd circle
			(at 0.40005 0)
			(size 0 0)
			(layers "F.Cu" "F.Mask" "F.Paste")
			(net "GND")
		)
	)
	(footprint ""
		(layer "F.Cu")
		(at 336.467704 -54.067456)
		(property "Reference" "PR237"
			(at 0 0 0)
			(layer "F.SilkS")
			(hide yes)
			(effects
				(font
					(size 1.27 1.27)
				)
			)
		)
		(property "Value" ""
			(at 0 0 0)
			(layer "F.Fab")
			(effects
				(font
					(size 1.27 1.27)
				)
			)
		)
		(duplicate_pad_numbers_are_jumpers no)
		(fp_line
			(start -0.7874 -0.4064)
			(end 0.7874 -0.4064)
			(stroke
				(width 0.1524)
				(type default)
			)
			(layer "F.SilkS")
		)
		(fp_line
			(start -0.7874 0.4064)
			(end -0.7874 -0.4064)
			(stroke
				(width 0.1524)
				(type default)
			)
			(layer "F.SilkS")
		)
		(fp_line
			(start 0.7874 -0.4064)
			(end 0.7874 0.4064)
			(stroke
				(width 0.1524)
				(type default)
			)
			(layer "F.SilkS")
		)
		(fp_line
			(start 0.7874 0.4064)
			(end -0.7874 0.4064)
			(stroke
				(width 0.1524)
				(type default)
			)
			(layer "F.SilkS")
		)
		(fp_line
			(start -0.67945 -0.305054)
			(end -0.12065 -0.305054)
			(stroke
				(width 0.1)
				(type default)
			)
			(layer "F.Fab")
		)
		(fp_line
			(start -0.67945 0.3048)
			(end -0.67945 -0.305054)
			(stroke
				(width 0.1)
				(type default)
			)
			(layer "F.Fab")
		)
		(fp_line
			(start -0.12065 -0.305054)
			(end -0.12065 -0.2794)
			(stroke
				(width 0.1)
				(type default)
			)
			(layer "F.Fab")
		)
		(fp_line
			(start -0.12065 -0.2794)
			(end 0.12065 -0.2794)
			(stroke
				(width 0.1)
				(type default)
			)
			(layer "F.Fab")
		)
		(fp_line
			(start -0.12065 0.2794)
			(end -0.12065 0.3048)
			(stroke
				(width 0.1)
				(type default)
			)
			(layer "F.Fab")
		)
		(fp_line
			(start -0.12065 0.3048)
			(end -0.67945 0.3048)
			(stroke
				(width 0.1)
				(type default)
			)
			(layer "F.Fab")
		)
		(fp_line
			(start 0.120396 0.2794)
			(end -0.12065 0.2794)
			(stroke
				(width 0.1)
				(type default)
			)
			(layer "F.Fab")
		)
		(fp_line
			(start 0.120396 0.3048)
			(end 0.120396 0.2794)
			(stroke
				(width 0.1)
				(type default)
			)
			(layer "F.Fab")
		)
		(fp_line
			(start 0.12065 -0.3048)
			(end 0.67945 -0.3048)
			(stroke
				(width 0.1)
				(type default)
			)
			(layer "F.Fab")
		)
		(fp_line
			(start 0.12065 -0.2794)
			(end 0.12065 -0.3048)
			(stroke
				(width 0.1)
				(type default)
			)
			(layer "F.Fab")
		)
		(fp_line
			(start 0.67945 -0.3048)
			(end 0.67945 0.3048)
			(stroke
				(width 0.1)
				(type default)
			)
			(layer "F.Fab")
		)
		(fp_line
			(start 0.67945 0.3048)
			(end 0.120396 0.3048)
			(stroke
				(width 0.1)
				(type default)
			)
			(layer "F.Fab")
		)
		(pad "1" smd circle
			(at -0.40005 0)
			(size 0 0)
			(layers "F.Cu" "F.Mask" "F.Paste")
			(net "P12V_SSD11_OCP")
		)
		(pad "2" smd circle
			(at 0.40005 0)
			(size 0 0)
			(layers "F.Cu" "F.Mask" "F.Paste")
			(net "GND")
		)
	)
)
